# BASEBOARD_FAB2 (Tioga Pass) — schematic netlist excerpt (pin names and nets, part order shuffled) for the footprints in the layout excerpt that follows; sources: Cadence DE-HDL packaged netlist, KiCad conversion of Wiwynn_Tioga_Pass_MB.brd

C25W70  CAP  4.7UF 6.3V 10% X6S  pkg 0603  page 149 : A = P3V3_USB2A_ALG ; B = GND
R9M17  RES  2.0K 1% CHIP  pkg 0402  page 163 : A = P3V3_STBY ; B = SMB_PEHPCPU1_STBY_LVC3_R_SCL
C9R7  CAP  10UF 16V 10% X6S  pkg 0805  page 207 : A = VR_FET_SW_P12V_STBY_PVCCIN_CPU1 ; B = GND

(kicad_pcb
	(version 20260206)
	(generator "pcbnew")
	(generator_version "10.0")
	(general
		(thickness 1.6)
		(legacy_teardrops no)
	)
	(paper "A4")
	(title_block
		(title "Wiwynn_Tioga_Pass_MB.brd")
		(comment 1 "Tioga Pass / footprints 4677-4679 of 4770")
	)
	(layers
		(0 "F.Cu" signal "TOP")
		(4 "In1.Cu" signal "L2GND")
		(6 "In2.Cu" signal "L3")
		(8 "In3.Cu" signal "L4GND")
		(10 "In4.Cu" signal "L5")
		(12 "In5.Cu" signal "L6GND")
		(14 "In6.Cu" signal "L7VCC")
		(16 "In7.Cu" signal "L8VCC")
		(18 "In8.Cu" signal "L9GND")
		(20 "In9.Cu" signal "L10")
		(22 "In10.Cu" signal "L11GND")
		(24 "In11.Cu" signal "L12")
		(26 "In12.Cu" signal "L13GND")
		(2 "B.Cu" signal "BOTTOM")
		(9 "F.Adhes" user "F.Adhesive")
		(11 "B.Adhes" user "B.Adhesive")
		(13 "F.Paste" user "Package Geometry/Pastemask Top")
		(15 "B.Paste" user "Package Geometry/Pastemask Bottom")
		(5 "F.SilkS" user "Ref Des/Silkscreen Top")
		(7 "B.SilkS" user "Ref Des/Silkscreen Bottom")
		(1 "F.Mask" user "Board Geometry/Soldermask Top")
		(3 "B.Mask" user "Board Geometry/Soldermask Bottom")
		(17 "Dwgs.User" user "User.Drawings")
		(19 "Cmts.User" user "User.Comments")
		(21 "Eco1.User" user "User.Eco1")
		(23 "Eco2.User" user "User.Eco2")
		(25 "Edge.Cuts" user "Board Geometry/Outline")
		(27 "Margin" user)
		(31 "F.CrtYd" user "Package Geometry/Place Bound Top")
		(29 "B.CrtYd" user "Package Geometry/Place Bound Bottom")
		(35 "F.Fab" user "Ref Des/Assembly Top")
		(33 "B.Fab" user "Ref Des/Assembly Bottom")
	)
	(footprint ""
		(layer "B.Cu")
		(at 32.832802 -59.973464 90)
		(property "Reference" "C9R7"
			(at 0 0 90)
			(layer "B.SilkS")
			(hide yes)
			(effects
				(font
					(size 1.27 1.27)
				)
				(justify mirror)
			)
		)
		(property "Value" ""
			(at 0 0 90)
			(layer "B.Fab")
			(effects
				(font
					(size 1.27 1.27)
				)
				(justify mirror)
			)
		)
		(duplicate_pad_numbers_are_jumpers no)
		(fp_poly
			(pts
				(xy 0.7239 -0.2159) (xy -0.7239 -0.2159) (xy -0.7239 1.9939) (xy 0.7239 1.9939)
			)
			(stroke
				(width 0)
				(type default)
			)
			(fill no)
			(layer "B.CrtYd")
		)
		(fp_line
			(start 0.7239 -0.2159)
			(end 0.7239 1.9939)
			(stroke
				(width 0.1)
				(type default)
			)
			(layer "B.Fab")
		)
		(fp_line
			(start -0.7239 -0.2159)
			(end 0.7239 -0.2159)
			(stroke
				(width 0.1)
				(type default)
			)
			(layer "B.Fab")
		)
		(fp_line
			(start 0.7239 1.9939)
			(end -0.7239 1.9939)
			(stroke
				(width 0.1)
				(type default)
			)
			(layer "B.Fab")
		)
		(fp_line
			(start -0.7239 1.9939)
			(end -0.7239 -0.2159)
			(stroke
				(width 0.1)
				(type default)
			)
			(layer "B.Fab")
		)
		(pad "1" smd rect
			(at 0 0 270)
			(size 1.27 1.016)
			(layers "B.Cu" "B.Mask" "B.Paste")
			(net "VR_FET_SW_P12V_STBY_PVCCIN_CPU1")
		)
		(pad "2" smd rect
			(at 0 1.778 270)
			(size 1.27 1.016)
			(layers "B.Cu" "B.Mask" "B.Paste")
			(net "GND")
		)
		(zone
			(layer "B.Cu")
			(hatch none 0.5)
			(connect_pads
				(clearance 0)
			)
			(min_thickness 0.25)
			(keepout
				(tracks not_allowed)
				(vias allowed)
				(pads allowed)
				(copperpour not_allowed)
				(footprints allowed)
			)
			(placement
				(enabled no)
				(sheetname "")
			)
			(fill
				(thermal_gap 0.5)
				(thermal_bridge_width 0.5)
				(island_removal_mode 0)
			)
			(polygon
				(pts
					(xy 33.340802 -60.608464) (xy 33.340802 -59.338464) (xy 34.102802 -59.338464) (xy 34.102802 -60.608464)
				)
			)
		)
	)
	(footprint ""
		(layer "B.Cu")
		(at 401.412456 -31.000446)
		(property "Reference" "C25W70"
			(at -0.97536 0.76708 90)
			(unlocked yes)
			(layer "B.SilkS")
			(effects
				(font
					(size 0.4064 0.254)
					(thickness 0.1524)
				)
				(justify mirror)
			)
		)
		(property "Value" ""
			(at 0 0 0)
			(layer "B.Fab")
			(effects
				(font
					(size 1.27 1.27)
				)
				(justify mirror)
			)
		)
		(duplicate_pad_numbers_are_jumpers no)
		(fp_poly
			(pts
				(xy 0.4953 -0.2032) (xy -0.4953 -0.2032) (xy -0.4953 1.6002) (xy 0.4953 1.6002)
			)
			(stroke
				(width 0)
				(type default)
			)
			(fill no)
			(layer "B.CrtYd")
		)
		(fp_line
			(start -0.4953 -0.2032)
			(end -0.4953 1.6002)
			(stroke
				(width 0.1)
				(type default)
			)
			(layer "B.Fab")
		)
		(fp_line
			(start -0.4953 1.6002)
			(end 0.4953 1.6002)
			(stroke
				(width 0.1)
				(type default)
			)
			(layer "B.Fab")
		)
		(fp_line
			(start 0.4953 -0.2032)
			(end -0.4953 -0.2032)
			(stroke
				(width 0.1)
				(type default)
			)
			(layer "B.Fab")
		)
		(fp_line
			(start 0.4953 1.6002)
			(end 0.4953 -0.2032)
			(stroke
				(width 0.1)
				(type default)
			)
			(layer "B.Fab")
		)
		(pad "1" smd rect
			(at 0 0 180)
			(size 0.762 0.889)
			(layers "B.Cu" "B.Mask" "B.Paste")
			(net "P3V3_USB2A_ALG")
		)
		(pad "2" smd rect
			(at 0 1.397 180)
			(size 0.762 0.889)
			(layers "B.Cu" "B.Mask" "B.Paste")
			(net "GND")
		)
		(zone
			(layer "B.Cu")
			(hatch none 0.5)
			(connect_pads
				(clearance 0)
			)
			(min_thickness 0.25)
			(keepout
				(tracks not_allowed)
				(vias allowed)
				(pads allowed)
				(copperpour not_allowed)
				(footprints allowed)
			)
			(placement
				(enabled no)
				(sheetname "")
			)
			(fill
				(thermal_gap 0.5)
				(thermal_bridge_width 0.5)
				(island_removal_mode 0)
			)
			(polygon
				(pts
					(xy 401.793456 -30.555946) (xy 401.031456 -30.555946) (xy 401.031456 -30.047946) (xy 401.793456 -30.047946)
				)
			)
		)
	)
	(footprint ""
		(layer "B.Cu")
		(at -2.20726 -119.46636 180)
		(property "Reference" "R9M17"
			(at 0 0 0)
			(layer "B.SilkS")
			(hide yes)
			(effects
				(font
					(size 1.27 1.27)
				)
				(justify mirror)
			)
		)
		(property "Value" ""
			(at 0 0 0)
			(layer "B.Fab")
			(effects
				(font
					(size 1.27 1.27)
				)
				(justify mirror)
			)
		)
		(duplicate_pad_numbers_are_jumpers no)
		(fp_rect
			(start 0.2794 -0.1016)
			(end -0.2794 0.9906)
			(stroke
				(width 0)
				(type default)
			)
			(fill no)
			(layer "B.CrtYd")
		)
		(fp_line
			(start 0.2794 0.9906)
			(end -0.2794 0.9906)
			(stroke
				(width 0.1)
				(type default)
			)
			(layer "B.Fab")
		)
		(fp_line
			(start 0.2794 -0.1016)
			(end 0.2794 0.9906)
			(stroke
				(width 0.1)
				(type default)
			)
			(layer "B.Fab")
		)
		(fp_line
			(start -0.2794 0.9906)
			(end -0.2794 -0.1016)
			(stroke
				(width 0.1)
				(type default)
			)
			(layer "B.Fab")
		)
		(fp_line
			(start -0.2794 -0.1016)
			(end 0.2794 -0.1016)
			(stroke
				(width 0.1)
				(type default)
			)
			(layer "B.Fab")
		)
		(pad "1" smd rect
			(at 0 0)
			(size 0.508 0.508)
			(layers "B.Cu" "B.Mask" "B.Paste")
			(net "P3V3_STBY")
		)
		(pad "2" smd rect
			(at 0 0.889)
			(size 0.508 0.508)
			(layers "B.Cu" "B.Mask" "B.Paste")
			(net "SMB_PEHPCPU1_STBY_LVC3_R_SCL")
		)
		(zone
			(layer "B.Cu")
			(hatch none 0.5)
			(connect_pads
				(clearance 0)
			)
			(min_thickness 0.25)
			(keepout
				(tracks not_allowed)
				(vias allowed)
				(pads allowed)
				(copperpour not_allowed)
				(footprints allowed)
			)
			(placement
				(enabled no)
				(sheetname "")
			)
			(fill
				(thermal_gap 0.5)
				(thermal_bridge_width 0.5)
				(island_removal_mode 0)
			)
			(polygon
				(pts
					(xy -2.46126 -119.72036) (xy -1.95326 -119.72036) (xy -1.95326 -120.10136) (xy -2.46126 -120.10136)
				)
			)
		)
		(zone
			(layer "B.Cu")
			(hatch none 0.5)
			(connect_pads
				(clearance 0)
			)
			(min_thickness 0.25)
			(keepout
				(tracks allowed)
				(vias not_allowed)
				(pads allowed)
				(copperpour not_allowed)
				(footprints allowed)
			)
			(placement
				(enabled no)
				(sheetname "")
			)
			(fill
				(thermal_gap 0.5)
				(thermal_bridge_width 0.5)
				(island_removal_mode 0)
			)
			(polygon
				(pts
					(xy -2.46126 -119.72036) (xy -1.95326 -119.72036) (xy -1.95326 -120.10136) (xy -2.46126 -120.10136)
				)
			)
		)
	)
)
